(kicad_pcb
	(version 20260206)
	(generator "pcbnew")
	(generator_version "10.0")
	(general
		(thickness 1.6)
		(legacy_teardrops no)
	)
	(paper "A4")
	(title_block
		(title "panther-plus-userver — 13130-1b_20150205.brd")
		(comment 1 "Honey Badger (Wiwynn) / footprint 1214 of 1509 (DIMM3), pads 163-169 of 210")
	)
	(layers
		(0 "F.Cu" signal "TOP")
		(4 "In1.Cu" signal "L2")
		(6 "In2.Cu" signal "L3")
		(8 "In3.Cu" signal "L4")
		(10 "In4.Cu" signal "L5")
		(12 "In5.Cu" signal "L6")
		(14 "In6.Cu" signal "L7")
		(16 "In7.Cu" signal "L8")
		(18 "In8.Cu" signal "L9")
		(20 "In9.Cu" signal "L10")
		(22 "In10.Cu" signal "L11")
		(2 "B.Cu" signal "BOTTOM")
		(9 "F.Adhes" user "F.Adhesive")
		(11 "B.Adhes" user "B.Adhesive")
		(13 "F.Paste" user "Package Geometry/Pastemask Top")
		(15 "B.Paste" user "Package Geometry/Pastemask Bottom")
		(5 "F.SilkS" user "Ref Des/Silkscreen Top")
		(7 "B.SilkS" user "Ref Des/Silkscreen Bottom")
		(1 "F.Mask" user "Board Geometry/Soldermask Top")
		(3 "B.Mask" user "Board Geometry/Soldermask Bottom")
		(17 "Dwgs.User" user "User.Drawings")
		(19 "Cmts.User" user "User.Comments")
		(21 "Eco1.User" user "User.Eco1")
		(23 "Eco2.User" user "User.Eco2")
		(25 "Edge.Cuts" user "Board Geometry/Outline")
		(27 "Margin" user)
		(31 "F.CrtYd" user "Package Geometry/Place Bound Top")
		(29 "B.CrtYd" user "Package Geometry/Place Bound Bottom")
		(35 "F.Fab" user "Ref Des/Assembly Top")
		(33 "B.Fab" user "Ref Des/Assembly Bottom")
	)
	(footprint ""
		(layer "B.Cu")
		(at 159.999934 -5.790692)
		(property "Reference" "DIMM3"
			(at 0 0 0)
			(layer "B.SilkS")
			(hide yes)
			(effects
				(font
					(size 1.27 1.27)
				)
				(justify mirror)
			)
		)
		(property "Value" "DDR3-204P-142-COLAY-1-GP-U"
			(at 41.312338 -16.676878 0)
			(unlocked yes)
			(layer "B.Fab")
			(hide yes)
			(effects
				(font
					(size 1.016 1.016)
					(thickness 0.1524)
				)
				(justify mirror)
			)
		)
		(property "Device Type" "AS0A626-J8R6-7H-COLAY-1"
			(at 41.312338 -18.200878 0)
			(unlocked yes)
			(layer "B.Fab")
			(hide yes)
			(effects
				(font
					(size 1.016 1.016)
					(thickness 0.1524)
				)
				(justify mirror)
			)
		)
		(duplicate_pad_numbers_are_jumpers no)
		(pad "161" smd custom
			(at 18.750026 -4.100068 180)
			(size 0.1143 0.1143)
			(layers "B.Cu" "B.Mask" "B.Paste")
			(net "M_B_DQ43")
			(options
				(clearance outline)
				(anchor circle)
			)
			(primitives
				(gr_poly
					(pts
						(xy 0 -0.9017) (xy -0.03175 -0.89916) (xy -0.0635 -0.889) (xy -0.09144 -0.87376) (xy -0.11684 -0.85344)
						(xy -0.13716 -0.82804) (xy -0.1524 -0.8001) (xy -0.16256 -0.76835) (xy -0.1651 -0.7366) (xy -0.1651 -0.44958)
						(xy -0.17272 -0.44196) (xy -0.19812 -0.4064) (xy -0.2032 -0.39624) (xy -0.20701 -0.38735) (xy -0.21209 -0.37719)
						(xy -0.2159 -0.36703) (xy -0.21844 -0.35687) (xy -0.22225 -0.34544) (xy -0.22352 -0.33528) (xy -0.22606 -0.32512)
						(xy -0.22733 -0.31369) (xy -0.22733 -0.30353) (xy -0.2286 -0.2921) (xy -0.22733 -0.28067) (xy -0.22733 -0.27051)
						(xy -0.22606 -0.25908) (xy -0.22352 -0.24892) (xy -0.22225 -0.23876) (xy -0.21844 -0.22733) (xy -0.2159 -0.21717)
						(xy -0.21209 -0.20701) (xy -0.20701 -0.19685) (xy -0.2032 -0.18796) (xy -0.19812 -0.1778) (xy -0.17272 -0.14224)
						(xy -0.1651 -0.13462) (xy -0.1651 0.7366) (xy -0.16256 0.76835) (xy -0.1524 0.8001) (xy -0.13716 0.82804)
						(xy -0.11684 0.85344) (xy -0.09144 0.87376) (xy -0.0635 0.889) (xy -0.03175 0.89916) (xy 0 0.9017)
						(xy 0.03175 0.89916) (xy 0.0635 0.889) (xy 0.09144 0.87376) (xy 0.11684 0.85344) (xy 0.13716 0.82804)
						(xy 0.1524 0.8001) (xy 0.16256 0.76835) (xy 0.1651 0.7366) (xy 0.1651 -0.13462) (xy 0.17272 -0.14224)
						(xy 0.19812 -0.1778) (xy 0.2032 -0.18796) (xy 0.20701 -0.19685) (xy 0.21209 -0.20701) (xy 0.2159 -0.21717)
						(xy 0.21844 -0.22733) (xy 0.22225 -0.23876) (xy 0.22352 -0.24892) (xy 0.22606 -0.25908) (xy 0.22733 -0.27051)
						(xy 0.22733 -0.28067) (xy 0.2286 -0.2921) (xy 0.22733 -0.30353) (xy 0.22733 -0.31369) (xy 0.22606 -0.32512)
						(xy 0.22352 -0.33528) (xy 0.22225 -0.34544) (xy 0.21844 -0.35687) (xy 0.2159 -0.36703) (xy 0.21209 -0.37719)
						(xy 0.20701 -0.38735) (xy 0.2032 -0.39624) (xy 0.19812 -0.4064) (xy 0.17272 -0.44196) (xy 0.1651 -0.44958)
						(xy 0.1651 -0.7366) (xy 0.16256 -0.76835) (xy 0.1524 -0.8001) (xy 0.13716 -0.82804) (xy 0.11684 -0.85344)
						(xy 0.09144 -0.87376) (xy 0.0635 -0.889) (xy 0.03175 -0.89916)
					)
					(width 0)
					(fill yes)
				)
			)
		)
		(pad "162" smd custom
			(at 19.05 4.100068 180)
			(size 0.1143 0.1143)
			(layers "B.Cu" "B.Mask" "B.Paste")
			(net "M_B_DQ47")
			(options
				(clearance outline)
				(anchor circle)
			)
			(primitives
				(gr_poly
					(pts
						(xy 0 -0.9017) (xy -0.03175 -0.89916) (xy -0.0635 -0.889) (xy -0.09144 -0.87376) (xy -0.11684 -0.85344)
						(xy -0.13716 -0.82804) (xy -0.1524 -0.8001) (xy -0.16256 -0.76835) (xy -0.1651 -0.7366) (xy -0.1651 0.13462)
						(xy -0.17272 0.14224) (xy -0.19812 0.1778) (xy -0.2032 0.18796) (xy -0.20701 0.19685) (xy -0.21209 0.20701)
						(xy -0.2159 0.21717) (xy -0.21844 0.22733) (xy -0.22225 0.23876) (xy -0.22352 0.24892) (xy -0.22606 0.25908)
						(xy -0.22733 0.27051) (xy -0.22733 0.28067) (xy -0.2286 0.2921) (xy -0.22733 0.30353) (xy -0.22733 0.31369)
						(xy -0.22606 0.32512) (xy -0.22352 0.33528) (xy -0.22225 0.34544) (xy -0.21844 0.35687) (xy -0.2159 0.36703)
						(xy -0.21209 0.37719) (xy -0.20701 0.38735) (xy -0.2032 0.39624) (xy -0.19812 0.4064) (xy -0.17272 0.44196)
						(xy -0.1651 0.44958) (xy -0.1651 0.7366) (xy -0.16256 0.76835) (xy -0.1524 0.8001) (xy -0.13716 0.82804)
						(xy -0.11684 0.85344) (xy -0.09144 0.87376) (xy -0.0635 0.889) (xy -0.03175 0.89916) (xy 0 0.9017)
						(xy 0.03175 0.89916) (xy 0.0635 0.889) (xy 0.09144 0.87376) (xy 0.11684 0.85344) (xy 0.13716 0.82804)
						(xy 0.1524 0.8001) (xy 0.16256 0.76835) (xy 0.1651 0.7366) (xy 0.1651 0.44958) (xy 0.17272 0.44196)
						(xy 0.19812 0.4064) (xy 0.2032 0.39624) (xy 0.20701 0.38735) (xy 0.21209 0.37719) (xy 0.2159 0.36703)
						(xy 0.21844 0.35687) (xy 0.22225 0.34544) (xy 0.22352 0.33528) (xy 0.22606 0.32512) (xy 0.22733 0.31369)
						(xy 0.22733 0.30353) (xy 0.2286 0.2921) (xy 0.22733 0.28067) (xy 0.22733 0.27051) (xy 0.22606 0.25908)
						(xy 0.22352 0.24892) (xy 0.22225 0.23876) (xy 0.21844 0.22733) (xy 0.2159 0.21717) (xy 0.21209 0.20701)
						(xy 0.20701 0.19685) (xy 0.2032 0.18796) (xy 0.19812 0.1778) (xy 0.17272 0.14224) (xy 0.1651 0.13462)
						(xy 0.1651 -0.7366) (xy 0.16256 -0.76835) (xy 0.1524 -0.8001) (xy 0.13716 -0.82804) (xy 0.11684 -0.85344)
						(xy 0.09144 -0.87376) (xy 0.0635 -0.889) (xy 0.03175 -0.89916)
					)
					(width 0)
					(fill yes)
				)
			)
		)
		(pad "163" smd custom
			(at 19.349974 -4.100068 180)
			(size 0.1143 0.1143)
			(layers "B.Cu" "B.Mask" "B.Paste")
			(net "GND")
			(options
				(clearance outline)
				(anchor circle)
			)
			(primitives
				(gr_poly
					(pts
						(xy 0 -0.9017) (xy -0.03175 -0.89916) (xy -0.0635 -0.889) (xy -0.09144 -0.87376) (xy -0.11684 -0.85344)
						(xy -0.13716 -0.82804) (xy -0.1524 -0.8001) (xy -0.16256 -0.76835) (xy -0.1651 -0.7366) (xy -0.1651 -0.19685)
						(xy -0.17272 -0.18923) (xy -0.17907 -0.18034) (xy -0.18669 -0.17145) (xy -0.19177 -0.16256) (xy -0.19812 -0.15367)
						(xy -0.20828 -0.13335) (xy -0.21971 -0.10287) (xy -0.22225 -0.09271) (xy -0.22479 -0.08128) (xy -0.22606 -0.07112)
						(xy -0.2286 -0.05969) (xy -0.2286 -0.01651) (xy -0.22606 -0.00508) (xy -0.22479 0.00508) (xy -0.22225 0.01651)
						(xy -0.21971 0.02667) (xy -0.20828 0.05715) (xy -0.19812 0.07747) (xy -0.19177 0.08636) (xy -0.18669 0.09525)
						(xy -0.17907 0.10414) (xy -0.17272 0.11303) (xy -0.1651 0.12065) (xy -0.1651 0.7366) (xy -0.16256 0.76835)
						(xy -0.1524 0.8001) (xy -0.13716 0.82804) (xy -0.11684 0.85344) (xy -0.09144 0.87376) (xy -0.0635 0.889)
						(xy -0.03175 0.89916) (xy 0 0.9017) (xy 0.03175 0.89916) (xy 0.0635 0.889) (xy 0.09144 0.87376)
						(xy 0.11684 0.85344) (xy 0.13716 0.82804) (xy 0.1524 0.8001) (xy 0.16256 0.76835) (xy 0.1651 0.7366)
						(xy 0.1651 0.11938) (xy 0.17272 0.11176) (xy 0.19812 0.0762) (xy 0.2032 0.06604) (xy 0.20701 0.05715)
						(xy 0.21209 0.04699) (xy 0.2159 0.03683) (xy 0.21844 0.02667) (xy 0.22225 0.01524) (xy 0.22352 0.00508)
						(xy 0.22606 -0.00508) (xy 0.22733 -0.01651) (xy 0.22733 -0.02667) (xy 0.2286 -0.0381) (xy 0.22733 -0.04953)
						(xy 0.22733 -0.05969) (xy 0.22606 -0.07112) (xy 0.22352 -0.08128) (xy 0.22225 -0.09144) (xy 0.21844 -0.10287)
						(xy 0.2159 -0.11303) (xy 0.21209 -0.12319) (xy 0.20701 -0.13335) (xy 0.2032 -0.14224) (xy 0.19812 -0.1524)
						(xy 0.17272 -0.18796) (xy 0.1651 -0.19558) (xy 0.1651 -0.7366) (xy 0.16256 -0.76835) (xy 0.1524 -0.8001)
						(xy 0.13716 -0.82804) (xy 0.11684 -0.85344) (xy 0.09144 -0.87376) (xy 0.0635 -0.889) (xy 0.03175 -0.89916)
					)
					(width 0)
					(fill yes)
				)
			)
		)
		(pad "164" smd custom
			(at 19.649948 4.100068 180)
			(size 0.1143 0.1143)
			(layers "B.Cu" "B.Mask" "B.Paste")
			(net "GND")
			(options
				(clearance outline)
				(anchor circle)
			)
			(primitives
				(gr_poly
					(pts
						(xy 0 -0.9017) (xy -0.03175 -0.89916) (xy -0.0635 -0.889) (xy -0.09144 -0.87376) (xy -0.11684 -0.85344)
						(xy -0.13716 -0.82804) (xy -0.1524 -0.8001) (xy -0.16256 -0.76835) (xy -0.1651 -0.7366) (xy -0.1651 -0.11938)
						(xy -0.17272 -0.11176) (xy -0.19812 -0.0762) (xy -0.2032 -0.06604) (xy -0.20701 -0.05715) (xy -0.21209 -0.04699)
						(xy -0.2159 -0.03683) (xy -0.21844 -0.02667) (xy -0.22225 -0.01524) (xy -0.22352 -0.00508) (xy -0.22606 0.00508)
						(xy -0.22733 0.01651) (xy -0.22733 0.02667) (xy -0.2286 0.0381) (xy -0.22733 0.04953) (xy -0.22733 0.05969)
						(xy -0.22606 0.07112) (xy -0.22352 0.08128) (xy -0.22225 0.09144) (xy -0.21844 0.10287) (xy -0.2159 0.11303)
						(xy -0.21209 0.12319) (xy -0.20701 0.13335) (xy -0.2032 0.14224) (xy -0.19812 0.1524) (xy -0.17272 0.18796)
						(xy -0.1651 0.19558) (xy -0.1651 0.7366) (xy -0.16256 0.76835) (xy -0.1524 0.8001) (xy -0.13716 0.82804)
						(xy -0.11684 0.85344) (xy -0.09144 0.87376) (xy -0.0635 0.889) (xy -0.03175 0.89916) (xy 0 0.9017)
						(xy 0.03175 0.89916) (xy 0.0635 0.889) (xy 0.09144 0.87376) (xy 0.11684 0.85344) (xy 0.13716 0.82804)
						(xy 0.1524 0.8001) (xy 0.16256 0.76835) (xy 0.1651 0.7366) (xy 0.1651 0.19685) (xy 0.17272 0.18923)
						(xy 0.17907 0.18034) (xy 0.18669 0.17145) (xy 0.19177 0.16256) (xy 0.19812 0.15367) (xy 0.20828 0.13335)
						(xy 0.21971 0.10287) (xy 0.22225 0.09271) (xy 0.22479 0.08128) (xy 0.22606 0.07112) (xy 0.2286 0.05969)
						(xy 0.2286 0.01651) (xy 0.22606 0.00508) (xy 0.22479 -0.00508) (xy 0.22225 -0.01651) (xy 0.21971 -0.02667)
						(xy 0.20828 -0.05715) (xy 0.19812 -0.07747) (xy 0.19177 -0.08636) (xy 0.18669 -0.09525) (xy 0.17907 -0.10414)
						(xy 0.17272 -0.11303) (xy 0.1651 -0.12065) (xy 0.1651 -0.7366) (xy 0.16256 -0.76835) (xy 0.1524 -0.8001)
						(xy 0.13716 -0.82804) (xy 0.11684 -0.85344) (xy 0.09144 -0.87376) (xy 0.0635 -0.889) (xy 0.03175 -0.89916)
					)
					(width 0)
					(fill yes)
				)
			)
		)
		(pad "165" smd custom
			(at 19.949922 -4.100068 180)
			(size 0.1143 0.1143)
			(layers "B.Cu" "B.Mask" "B.Paste")
			(net "M_B_DQ48")
			(options
				(clearance outline)
				(anchor circle)
			)
			(primitives
				(gr_poly
					(pts
						(xy 0 -0.9017) (xy -0.03175 -0.89916) (xy -0.0635 -0.889) (xy -0.09144 -0.87376) (xy -0.11684 -0.85344)
						(xy -0.13716 -0.82804) (xy -0.1524 -0.8001) (xy -0.16256 -0.76835) (xy -0.1651 -0.7366) (xy -0.1651 -0.44958)
						(xy -0.17272 -0.44196) (xy -0.19812 -0.4064) (xy -0.2032 -0.39624) (xy -0.20701 -0.38735) (xy -0.21209 -0.37719)
						(xy -0.2159 -0.36703) (xy -0.21844 -0.35687) (xy -0.22225 -0.34544) (xy -0.22352 -0.33528) (xy -0.22606 -0.32512)
						(xy -0.22733 -0.31369) (xy -0.22733 -0.30353) (xy -0.2286 -0.2921) (xy -0.22733 -0.28067) (xy -0.22733 -0.27051)
						(xy -0.22606 -0.25908) (xy -0.22352 -0.24892) (xy -0.22225 -0.23876) (xy -0.21844 -0.22733) (xy -0.2159 -0.21717)
						(xy -0.21209 -0.20701) (xy -0.20701 -0.19685) (xy -0.2032 -0.18796) (xy -0.19812 -0.1778) (xy -0.17272 -0.14224)
						(xy -0.1651 -0.13462) (xy -0.1651 0.7366) (xy -0.16256 0.76835) (xy -0.1524 0.8001) (xy -0.13716 0.82804)
						(xy -0.11684 0.85344) (xy -0.09144 0.87376) (xy -0.0635 0.889) (xy -0.03175 0.89916) (xy 0 0.9017)
						(xy 0.03175 0.89916) (xy 0.0635 0.889) (xy 0.09144 0.87376) (xy 0.11684 0.85344) (xy 0.13716 0.82804)
						(xy 0.1524 0.8001) (xy 0.16256 0.76835) (xy 0.1651 0.7366) (xy 0.1651 -0.13462) (xy 0.17272 -0.14224)
						(xy 0.19812 -0.1778) (xy 0.2032 -0.18796) (xy 0.20701 -0.19685) (xy 0.21209 -0.20701) (xy 0.2159 -0.21717)
						(xy 0.21844 -0.22733) (xy 0.22225 -0.23876) (xy 0.22352 -0.24892) (xy 0.22606 -0.25908) (xy 0.22733 -0.27051)
						(xy 0.22733 -0.28067) (xy 0.2286 -0.2921) (xy 0.22733 -0.30353) (xy 0.22733 -0.31369) (xy 0.22606 -0.32512)
						(xy 0.22352 -0.33528) (xy 0.22225 -0.34544) (xy 0.21844 -0.35687) (xy 0.2159 -0.36703) (xy 0.21209 -0.37719)
						(xy 0.20701 -0.38735) (xy 0.2032 -0.39624) (xy 0.19812 -0.4064) (xy 0.17272 -0.44196) (xy 0.1651 -0.44958)
						(xy 0.1651 -0.7366) (xy 0.16256 -0.76835) (xy 0.1524 -0.8001) (xy 0.13716 -0.82804) (xy 0.11684 -0.85344)
						(xy 0.09144 -0.87376) (xy 0.0635 -0.889) (xy 0.03175 -0.89916)
					)
					(width 0)
					(fill yes)
				)
			)
		)
		(pad "166" smd custom
			(at 20.249896 4.100068 180)
			(size 0.1143 0.1143)
			(layers "B.Cu" "B.Mask" "B.Paste")
			(net "M_B_DQ52")
			(options
				(clearance outline)
				(anchor circle)
			)
			(primitives
				(gr_poly
					(pts
						(xy 0 -0.9017) (xy -0.03175 -0.89916) (xy -0.0635 -0.889) (xy -0.09144 -0.87376) (xy -0.11684 -0.85344)
						(xy -0.13716 -0.82804) (xy -0.1524 -0.8001) (xy -0.16256 -0.76835) (xy -0.1651 -0.7366) (xy -0.1651 0.13462)
						(xy -0.17272 0.14224) (xy -0.19812 0.1778) (xy -0.2032 0.18796) (xy -0.20701 0.19685) (xy -0.21209 0.20701)
						(xy -0.2159 0.21717) (xy -0.21844 0.22733) (xy -0.22225 0.23876) (xy -0.22352 0.24892) (xy -0.22606 0.25908)
						(xy -0.22733 0.27051) (xy -0.22733 0.28067) (xy -0.2286 0.2921) (xy -0.22733 0.30353) (xy -0.22733 0.31369)
						(xy -0.22606 0.32512) (xy -0.22352 0.33528) (xy -0.22225 0.34544) (xy -0.21844 0.35687) (xy -0.2159 0.36703)
						(xy -0.21209 0.37719) (xy -0.20701 0.38735) (xy -0.2032 0.39624) (xy -0.19812 0.4064) (xy -0.17272 0.44196)
						(xy -0.1651 0.44958) (xy -0.1651 0.7366) (xy -0.16256 0.76835) (xy -0.1524 0.8001) (xy -0.13716 0.82804)
						(xy -0.11684 0.85344) (xy -0.09144 0.87376) (xy -0.0635 0.889) (xy -0.03175 0.89916) (xy 0 0.9017)
						(xy 0.03175 0.89916) (xy 0.0635 0.889) (xy 0.09144 0.87376) (xy 0.11684 0.85344) (xy 0.13716 0.82804)
						(xy 0.1524 0.8001) (xy 0.16256 0.76835) (xy 0.1651 0.7366) (xy 0.1651 0.44958) (xy 0.17272 0.44196)
						(xy 0.19812 0.4064) (xy 0.2032 0.39624) (xy 0.20701 0.38735) (xy 0.21209 0.37719) (xy 0.2159 0.36703)
						(xy 0.21844 0.35687) (xy 0.22225 0.34544) (xy 0.22352 0.33528) (xy 0.22606 0.32512) (xy 0.22733 0.31369)
						(xy 0.22733 0.30353) (xy 0.2286 0.2921) (xy 0.22733 0.28067) (xy 0.22733 0.27051) (xy 0.22606 0.25908)
						(xy 0.22352 0.24892) (xy 0.22225 0.23876) (xy 0.21844 0.22733) (xy 0.2159 0.21717) (xy 0.21209 0.20701)
						(xy 0.20701 0.19685) (xy 0.2032 0.18796) (xy 0.19812 0.1778) (xy 0.17272 0.14224) (xy 0.1651 0.13462)
						(xy 0.1651 -0.7366) (xy 0.16256 -0.76835) (xy 0.1524 -0.8001) (xy 0.13716 -0.82804) (xy 0.11684 -0.85344)
						(xy 0.09144 -0.87376) (xy 0.0635 -0.889) (xy 0.03175 -0.89916)
					)
					(width 0)
					(fill yes)
				)
			)
		)
		(pad "167" smd custom
			(at 20.550124 -4.100068 180)
			(size 0.1143 0.1143)
			(layers "B.Cu" "B.Mask" "B.Paste")
			(net "M_B_DQ49")
			(options
				(clearance outline)
				(anchor circle)
			)
			(primitives
				(gr_poly
					(pts
						(xy 0 -0.9017) (xy -0.03175 -0.89916) (xy -0.0635 -0.889) (xy -0.09144 -0.87376) (xy -0.11684 -0.85344)
						(xy -0.13716 -0.82804) (xy -0.1524 -0.8001) (xy -0.16256 -0.76835) (xy -0.1651 -0.7366) (xy -0.1651 -0.19685)
						(xy -0.17272 -0.18923) (xy -0.17907 -0.18034) (xy -0.18669 -0.17145) (xy -0.19177 -0.16256) (xy -0.19812 -0.15367)
						(xy -0.20828 -0.13335) (xy -0.21971 -0.10287) (xy -0.22225 -0.09271) (xy -0.22479 -0.08128) (xy -0.22606 -0.07112)
						(xy -0.2286 -0.05969) (xy -0.2286 -0.01651) (xy -0.22606 -0.00508) (xy -0.22479 0.00508) (xy -0.22225 0.01651)
						(xy -0.21971 0.02667) (xy -0.20828 0.05715) (xy -0.19812 0.07747) (xy -0.19177 0.08636) (xy -0.18669 0.09525)
						(xy -0.17907 0.10414) (xy -0.17272 0.11303) (xy -0.1651 0.12065) (xy -0.1651 0.7366) (xy -0.16256 0.76835)
						(xy -0.1524 0.8001) (xy -0.13716 0.82804) (xy -0.11684 0.85344) (xy -0.09144 0.87376) (xy -0.0635 0.889)
						(xy -0.03175 0.89916) (xy 0 0.9017) (xy 0.03175 0.89916) (xy 0.0635 0.889) (xy 0.09144 0.87376)
						(xy 0.11684 0.85344) (xy 0.13716 0.82804) (xy 0.1524 0.8001) (xy 0.16256 0.76835) (xy 0.1651 0.7366)
						(xy 0.1651 0.11938) (xy 0.17272 0.11176) (xy 0.19812 0.0762) (xy 0.2032 0.06604) (xy 0.20701 0.05715)
						(xy 0.21209 0.04699) (xy 0.2159 0.03683) (xy 0.21844 0.02667) (xy 0.22225 0.01524) (xy 0.22352 0.00508)
						(xy 0.22606 -0.00508) (xy 0.22733 -0.01651) (xy 0.22733 -0.02667) (xy 0.2286 -0.0381) (xy 0.22733 -0.04953)
						(xy 0.22733 -0.05969) (xy 0.22606 -0.07112) (xy 0.22352 -0.08128) (xy 0.22225 -0.09144) (xy 0.21844 -0.10287)
						(xy 0.2159 -0.11303) (xy 0.21209 -0.12319) (xy 0.20701 -0.13335) (xy 0.2032 -0.14224) (xy 0.19812 -0.1524)
						(xy 0.17272 -0.18796) (xy 0.1651 -0.19558) (xy 0.1651 -0.7366) (xy 0.16256 -0.76835) (xy 0.1524 -0.8001)
						(xy 0.13716 -0.82804) (xy 0.11684 -0.85344) (xy 0.09144 -0.87376) (xy 0.0635 -0.889) (xy 0.03175 -0.89916)
					)
					(width 0)
					(fill yes)
				)
			)
		)
	)
)
